# SCM (Grand Teton) — schematic netlist excerpt (pin names and nets, part order shuffled) for the footprints in the layout excerpt that follows; sources: Cadence DE-HDL packaged netlist, KiCad conversion of 12092022_DA0F0TMDCD0_F0T_Management_Board_D_brd_V3_OCP.brd

R560  Q_RES  0 5% CHIP  pkg 0402LF  page 25 : A = FLASH_LATCH_Q_N_R1 ; B = FLASH_LATCH_Q_N_R2
PC256  Q_CAP  22UF 4V 20% X6S  pkg 0805  page 55 : A = P1V2_AUX ; B = GND

(kicad_pcb
	(version 20260206)
	(generator "pcbnew")
	(generator_version "10.0")
	(general
		(thickness 1.6)
		(legacy_teardrops no)
	)
	(paper "A4")
	(title_block
		(title "12092022_DA0F0TMDCD0_F0T_Management_Board_D_brd_V3_OCP.brd")
		(comment 1 "Grand Teton / footprints 118-119 of 1440")
	)
	(layers
		(0 "F.Cu" signal "TOP")
		(4 "In1.Cu" signal "GND")
		(6 "In2.Cu" signal "IN1")
		(8 "In3.Cu" signal "GND1")
		(10 "In4.Cu" signal "IN2")
		(12 "In5.Cu" signal "VCC")
		(14 "In6.Cu" signal "VCC1")
		(16 "In7.Cu" signal "IN3")
		(18 "In8.Cu" signal "GND2")
		(20 "In9.Cu" signal "IN4")
		(22 "In10.Cu" signal "GND3")
		(2 "B.Cu" signal "BOTTOM")
		(9 "F.Adhes" user "F.Adhesive")
		(11 "B.Adhes" user "B.Adhesive")
		(13 "F.Paste" user "Package Geometry/Pastemask Top")
		(15 "B.Paste" user "Package Geometry/Pastemask Bottom")
		(5 "F.SilkS" user "Ref Des/Silkscreen Top")
		(7 "B.SilkS" user "Ref Des/Silkscreen Bottom")
		(1 "F.Mask" user "Board Geometry/Soldermask Top")
		(3 "B.Mask" user "Board Geometry/Soldermask Bottom")
		(17 "Dwgs.User" user "User.Drawings")
		(19 "Cmts.User" user "User.Comments")
		(21 "Eco1.User" user "User.Eco1")
		(23 "Eco2.User" user "User.Eco2")
		(25 "Edge.Cuts" user "Board Geometry/Outline")
		(27 "Margin" user)
		(31 "F.CrtYd" user "Package Geometry/Place Bound Top")
		(29 "B.CrtYd" user "Package Geometry/Place Bound Bottom")
		(35 "F.Fab" user "Ref Des/Assembly Top")
		(33 "B.Fab" user "Ref Des/Assembly Bottom")
	)
	(footprint ""
		(layer "F.Cu")
		(at 83.952842 -59.047634 -90)
		(property "Reference" "PC256"
			(at 0 0 270)
			(layer "F.SilkS")
			(hide yes)
			(effects
				(font
					(size 1.27 1.27)
				)
			)
		)
		(property "Value" ""
			(at 0 0 270)
			(layer "F.Fab")
			(effects
				(font
					(size 1.27 1.27)
				)
			)
		)
		(duplicate_pad_numbers_are_jumpers no)
		(fp_line
			(start -1.651 0.8382)
			(end -1.651 -0.8382)
			(stroke
				(width 0.1524)
				(type default)
			)
			(layer "F.SilkS")
		)
		(fp_line
			(start 0 0.8382)
			(end 0 -0.8382)
			(stroke
				(width 0.1524)
				(type default)
			)
			(layer "F.SilkS")
		)
		(fp_line
			(start 1.651 0.8382)
			(end -1.651 0.8382)
			(stroke
				(width 0.1524)
				(type default)
			)
			(layer "F.SilkS")
		)
		(fp_line
			(start -1.651 -0.8382)
			(end 1.651 -0.8382)
			(stroke
				(width 0.1524)
				(type default)
			)
			(layer "F.SilkS")
		)
		(fp_line
			(start 1.651 -0.8382)
			(end 1.651 0.8382)
			(stroke
				(width 0.1524)
				(type default)
			)
			(layer "F.SilkS")
		)
		(fp_line
			(start -1.55956 0.7366)
			(end -1.524 0.7366)
			(stroke
				(width 0.1)
				(type default)
			)
			(layer "F.Fab")
		)
		(fp_line
			(start -1.524 0.7366)
			(end 1.524 0.7366)
			(stroke
				(width 0.1)
				(type default)
			)
			(layer "F.Fab")
		)
		(fp_line
			(start 1.524 0.7366)
			(end 1.55956 0.7366)
			(stroke
				(width 0.1)
				(type default)
			)
			(layer "F.Fab")
		)
		(fp_line
			(start 1.55956 0.7366)
			(end 1.55956 -0.7366)
			(stroke
				(width 0.1)
				(type default)
			)
			(layer "F.Fab")
		)
		(fp_line
			(start -1.55956 -0.7366)
			(end -1.55956 0.7366)
			(stroke
				(width 0.1)
				(type default)
			)
			(layer "F.Fab")
		)
		(fp_line
			(start -1.524 -0.7366)
			(end -1.55956 -0.7366)
			(stroke
				(width 0.1)
				(type default)
			)
			(layer "F.Fab")
		)
		(fp_line
			(start 1.524 -0.7366)
			(end -1.524 -0.7366)
			(stroke
				(width 0.1)
				(type default)
			)
			(layer "F.Fab")
		)
		(fp_line
			(start 1.55956 -0.7366)
			(end 1.524 -0.7366)
			(stroke
				(width 0.1)
				(type default)
			)
			(layer "F.Fab")
		)
		(pad "1" smd rect
			(at -0.94996 0 90)
			(size 1.1176 1.3716)
			(layers "F.Cu" "F.Mask" "F.Paste")
			(net "P1V2_AUX")
		)
		(pad "2" smd rect
			(at 0.94996 0 90)
			(size 1.1176 1.3716)
			(layers "F.Cu" "F.Mask" "F.Paste")
			(net "GND")
		)
	)
	(footprint ""
		(layer "F.Cu")
		(at 56.20004 -79.21244 90)
		(property "Reference" "R560"
			(at 0 0 90)
			(layer "F.SilkS")
			(hide yes)
			(effects
				(font
					(size 1.27 1.27)
				)
			)
		)
		(property "Value" ""
			(at 0 0 90)
			(layer "F.Fab")
			(effects
				(font
					(size 1.27 1.27)
				)
			)
		)
		(duplicate_pad_numbers_are_jumpers no)
		(fp_line
			(start 0.7874 -0.4064)
			(end 0.7874 0.4064)
			(stroke
				(width 0.1524)
				(type default)
			)
			(layer "F.SilkS")
		)
		(fp_line
			(start -0.7874 -0.4064)
			(end 0.7874 -0.4064)
			(stroke
				(width 0.1524)
				(type default)
			)
			(layer "F.SilkS")
		)
		(fp_line
			(start 0.7874 0.4064)
			(end -0.7874 0.4064)
			(stroke
				(width 0.1524)
				(type default)
			)
			(layer "F.SilkS")
		)
		(fp_line
			(start -0.7874 0.4064)
			(end -0.7874 -0.4064)
			(stroke
				(width 0.1524)
				(type default)
			)
			(layer "F.SilkS")
		)
		(fp_line
			(start -0.12065 -0.305054)
			(end -0.12065 -0.2794)
			(stroke
				(width 0.1)
				(type default)
			)
			(layer "F.Fab")
		)
		(fp_line
			(start -0.67945 -0.305054)
			(end -0.12065 -0.305054)
			(stroke
				(width 0.1)
				(type default)
			)
			(layer "F.Fab")
		)
		(fp_line
			(start 0.67945 -0.3048)
			(end 0.67945 0.3048)
			(stroke
				(width 0.1)
				(type default)
			)
			(layer "F.Fab")
		)
		(fp_line
			(start 0.12065 -0.3048)
			(end 0.67945 -0.3048)
			(stroke
				(width 0.1)
				(type default)
			)
			(layer "F.Fab")
		)
		(fp_line
			(start 0.12065 -0.2794)
			(end 0.12065 -0.3048)
			(stroke
				(width 0.1)
				(type default)
			)
			(layer "F.Fab")
		)
		(fp_line
			(start -0.12065 -0.2794)
			(end 0.12065 -0.2794)
			(stroke
				(width 0.1)
				(type default)
			)
			(layer "F.Fab")
		)
		(fp_line
			(start 0.120396 0.2794)
			(end -0.12065 0.2794)
			(stroke
				(width 0.1)
				(type default)
			)
			(layer "F.Fab")
		)
		(fp_line
			(start -0.12065 0.2794)
			(end -0.12065 0.3048)
			(stroke
				(width 0.1)
				(type default)
			)
			(layer "F.Fab")
		)
		(fp_line
			(start 0.67945 0.3048)
			(end 0.120396 0.3048)
			(stroke
				(width 0.1)
				(type default)
			)
			(layer "F.Fab")
		)
		(fp_line
			(start 0.120396 0.3048)
			(end 0.120396 0.2794)
			(stroke
				(width 0.1)
				(type default)
			)
			(layer "F.Fab")
		)
		(fp_line
			(start -0.12065 0.3048)
			(end -0.67945 0.3048)
			(stroke
				(width 0.1)
				(type default)
			)
			(layer "F.Fab")
		)
		(fp_line
			(start -0.67945 0.3048)
			(end -0.67945 -0.305054)
			(stroke
				(width 0.1)
				(type default)
			)
			(layer "F.Fab")
		)
		(pad "1" smd circle
			(at -0.40005 0 90)
			(size 0 0)
			(layers "F.Cu" "F.Mask" "F.Paste")
			(net "FLASH_LATCH_Q_N_R1")
		)
		(pad "2" smd circle
			(at 0.40005 0 90)
			(size 0 0)
			(layers "F.Cu" "F.Mask" "F.Paste")
			(net "FLASH_LATCH_Q_N_R2")
		)
	)
)
